(kicad_pcb
	(version 20260206)
	(generator "pcbnew")
	(generator_version "10.0")
	(general
		(thickness 1.6)
		(legacy_teardrops no)
	)
	(paper "A4")
	(title_block
		(title "03242023_DA0F0TMBIJ0_F0T_Motherboard_J_brd_V01_OCP.brd")
		(comment 1 "Grand Teton / footprint 3039 of 6105 (U2), pads 2036-2144 of 4677")
	)
	(layers
		(0 "F.Cu" signal "TOP")
		(4 "In1.Cu" signal "GND")
		(6 "In2.Cu" signal "IN1")
		(8 "In3.Cu" signal "GND1")
		(10 "In4.Cu" signal "IN2")
		(12 "In5.Cu" signal "GND2")
		(14 "In6.Cu" signal "IN3")
		(16 "In7.Cu" signal "GND3")
		(18 "In8.Cu" signal "VCC")
		(20 "In9.Cu" signal "VCC1")
		(22 "In10.Cu" signal "GND4")
		(24 "In11.Cu" signal "IN4")
		(26 "In12.Cu" signal "GND5")
		(28 "In13.Cu" signal "IN5")
		(30 "In14.Cu" signal "GND6")
		(32 "In15.Cu" signal "IN6")
		(34 "In16.Cu" signal "GND7")
		(2 "B.Cu" signal "BOTTOM")
		(9 "F.Adhes" user "F.Adhesive")
		(11 "B.Adhes" user "B.Adhesive")
		(13 "F.Paste" user "Package Geometry/Pastemask Top")
		(15 "B.Paste" user "Package Geometry/Pastemask Bottom")
		(5 "F.SilkS" user "Ref Des/Silkscreen Top")
		(7 "B.SilkS" user "Ref Des/Silkscreen Bottom")
		(1 "F.Mask" user "Board Geometry/Soldermask Top")
		(3 "B.Mask" user "Board Geometry/Soldermask Bottom")
		(17 "Dwgs.User" user "User.Drawings")
		(19 "Cmts.User" user "User.Comments")
		(21 "Eco1.User" user "User.Eco1")
		(23 "Eco2.User" user "User.Eco2")
		(25 "Edge.Cuts" user "Board Geometry/Outline")
		(27 "Margin" user)
		(31 "F.CrtYd" user "Package Geometry/Place Bound Top")
		(29 "B.CrtYd" user "Package Geometry/Place Bound Bottom")
		(35 "F.Fab" user "Ref Des/Assembly Top")
		(33 "B.Fab" user "Ref Des/Assembly Bottom")
	)
	(footprint ""
		(layer "F.Cu")
		(at 359.870248 -251.76988 90)
		(property "Reference" "U2"
			(at -74.416158 -44.488608 0)
			(unlocked yes)
			(layer "F.SilkS")
			(effects
				(font
					(size 1.6002 1.1938)
					(thickness 0.1524)
				)
				(justify left)
			)
		)
		(property "Value" ""
			(at 0 0 90)
			(layer "F.Fab")
			(effects
				(font
					(size 1.27 1.27)
				)
			)
		)
		(duplicate_pad_numbers_are_jumpers no)
		(pad "CL19" smd circle
			(at -22.77491 5.818886 270)
			(size 0.4318 0.4318)
			(layers "F.Cu" "F.Mask" "F.Paste")
			(net "DMI_CPU0_PCH_TX_DP<6>")
		)
		(pad "CL21" smd circle
			(at -21.147278 5.818886 270)
			(size 0.4318 0.4318)
			(layers "F.Cu" "F.Mask" "F.Paste")
			(net "TP_IBL_PLT_RST_SYNC_N")
		)
		(pad "CL23" smd circle
			(at -19.519392 5.818886 270)
			(size 0.4318 0.4318)
			(layers "F.Cu" "F.Mask" "F.Paste")
			(net "TP_I2C_S3M_RTC_CPU0_SCL")
		)
		(pad "CL25" smd circle
			(at -17.89176 5.818886 270)
			(size 0.4318 0.4318)
			(layers "F.Cu" "F.Mask" "F.Paste")
			(net "TP_H_SBLINK2_CPU0_PMSYNC")
		)
		(pad "CL60" smd circle
			(at 12.19454 5.928868 270)
			(size 0.4318 0.4318)
			(layers "F.Cu" "F.Mask" "F.Paste")
			(net "TP_CPU0_SPARE7")
		)
		(pad "CL62" smd circle
			(at 13.822426 5.928868 270)
			(size 0.4318 0.4318)
			(layers "F.Cu" "F.Mask" "F.Paste")
			(net "GND")
		)
		(pad "CL64" smd circle
			(at 15.450058 5.928868 270)
			(size 0.4318 0.4318)
			(layers "F.Cu" "F.Mask" "F.Paste")
			(net "NC_CPU0_VIEWPIN_DIE11<3>")
		)
		(pad "CL66" smd circle
			(at 17.07769 5.928868 270)
			(size 0.4318 0.4318)
			(layers "F.Cu" "F.Mask" "F.Paste")
			(net "TP_CPU0_SSC_SYNC")
		)
		(pad "CL68" smd circle
			(at 18.705576 5.928868 270)
			(size 0.4318 0.4318)
			(layers "F.Cu" "F.Mask" "F.Paste")
			(net "NC_CPU0_PE3_APROBE<0>")
		)
		(pad "CL70" smd circle
			(at 20.333462 5.928868 270)
			(size 0.4318 0.4318)
			(layers "F.Cu" "F.Mask" "F.Paste")
			(net "TP_CPU0_SPARE12")
		)
		(pad "CL72" smd circle
			(at 21.961094 5.928868 270)
			(size 0.4318 0.4318)
			(layers "F.Cu" "F.Mask" "F.Paste")
			(net "PUD_XTAL_CPU0_MODE0")
		)
		(pad "CL74" smd circle
			(at 23.58898 5.928868 270)
			(size 0.4318 0.4318)
			(layers "F.Cu" "F.Mask" "F.Paste")
			(net "GND")
		)
		(pad "CL76" smd circle
			(at 25.216612 5.928868 270)
			(size 0.4318 0.4318)
			(layers "F.Cu" "F.Mask" "F.Paste")
			(net "Net_667")
		)
		(pad "CL78" smd circle
			(at 26.844498 5.928868 270)
			(size 0.4318 0.4318)
			(layers "F.Cu" "F.Mask" "F.Paste")
			(net "GND")
		)
		(pad "CL80" smd circle
			(at 28.472384 5.928868 270)
			(size 0.4318 0.4318)
			(layers "F.Cu" "F.Mask" "F.Paste")
			(net "GND")
		)
		(pad "CL82" smd circle
			(at 30.100016 5.928868 270)
			(size 0.4318 0.4318)
			(layers "F.Cu" "F.Mask" "F.Paste")
			(net "GND")
		)
		(pad "CL84" smd circle
			(at 31.727902 5.928868 270)
			(size 0.4318 0.4318)
			(layers "F.Cu" "F.Mask" "F.Paste")
			(net "PVCCIN_CPU0")
		)
		(pad "CL86" smd circle
			(at 33.355534 5.928868 270)
			(size 0.4318 0.4318)
			(layers "F.Cu" "F.Mask" "F.Paste")
			(net "PVCCIN_CPU0")
		)
		(pad "CL88" smd circle
			(at 34.98342 5.928868 270)
			(size 0.4318 0.4318)
			(layers "F.Cu" "F.Mask" "F.Paste")
			(net "PVCCIN_CPU0")
		)
		(pad "CL90" smd circle
			(at 36.611306 5.928868 270)
			(size 0.4318 0.4318)
			(layers "F.Cu" "F.Mask" "F.Paste")
			(net "PVCCIN_CPU0")
		)
		(pad "CM2" smd circle
			(at -36.611306 6.288532 270)
			(size 0.4318 0.4318)
			(layers "F.Cu" "F.Mask" "F.Paste")
			(net "UPI_CPU1_CPU0_P0P1_DP<18>")
		)
		(pad "CM4" smd circle
			(at -34.98342 6.288532 270)
			(size 0.4318 0.4318)
			(layers "F.Cu" "F.Mask" "F.Paste")
			(net "GND")
		)
		(pad "CM6" smd circle
			(at -33.355534 6.288532 270)
			(size 0.4318 0.4318)
			(layers "F.Cu" "F.Mask" "F.Paste")
			(net "UPI_CPU0_CPU1_P1P0_DP<17>")
		)
		(pad "CM8" smd circle
			(at -31.727902 6.288532 270)
			(size 0.4318 0.4318)
			(layers "F.Cu" "F.Mask" "F.Paste")
			(net "GND")
		)
		(pad "CM10" smd circle
			(at -30.100016 6.288532 270)
			(size 0.4318 0.4318)
			(layers "F.Cu" "F.Mask" "F.Paste")
			(net "P5E_CPU0_PE1_RX_DP<1>")
		)
		(pad "CM12" smd circle
			(at -28.472384 6.288532 270)
			(size 0.4318 0.4318)
			(layers "F.Cu" "F.Mask" "F.Paste")
			(net "GND")
		)
		(pad "CM14" smd circle
			(at -26.844498 6.288532 270)
			(size 0.4318 0.4318)
			(layers "F.Cu" "F.Mask" "F.Paste")
			(net "P5E_CPU0_PE1_TX_DP<1>")
		)
		(pad "CM16" smd circle
			(at -25.216612 6.288532 270)
			(size 0.4318 0.4318)
			(layers "F.Cu" "F.Mask" "F.Paste")
			(net "GND")
		)
		(pad "CM18" smd circle
			(at -23.58898 6.288532 270)
			(size 0.4318 0.4318)
			(layers "F.Cu" "F.Mask" "F.Paste")
			(net "DMI_CPU0_PCH_TX_DN<7>")
		)
		(pad "CM20" smd circle
			(at -21.961094 6.288532 270)
			(size 0.4318 0.4318)
			(layers "F.Cu" "F.Mask" "F.Paste")
			(net "GND")
		)
		(pad "CM22" smd circle
			(at -20.333462 6.288532 270)
			(size 0.4318 0.4318)
			(layers "F.Cu" "F.Mask" "F.Paste")
			(net "GND")
		)
		(pad "CM24" smd circle
			(at -18.705576 6.288532 270)
			(size 0.4318 0.4318)
			(layers "F.Cu" "F.Mask" "F.Paste")
			(net "GND")
		)
		(pad "CM26" smd circle
			(at -17.07769 6.288532 270)
			(size 0.4318 0.4318)
			(layers "F.Cu" "F.Mask" "F.Paste")
			(net "TP_H_SBLINK3_CPU0_PMDOWN")
		)
		(pad "CM61" smd circle
			(at 13.008356 6.398514 270)
			(size 0.4318 0.4318)
			(layers "F.Cu" "F.Mask" "F.Paste")
			(net "GND")
		)
		(pad "CM63" smd circle
			(at 14.635988 6.398514 270)
			(size 0.4318 0.4318)
			(layers "F.Cu" "F.Mask" "F.Paste")
			(net "NC_CPU0_VIEWPIN_DIE11<2>")
		)
		(pad "CM65" smd circle
			(at 16.263874 6.398514 270)
			(size 0.4318 0.4318)
			(layers "F.Cu" "F.Mask" "F.Paste")
			(net "GND")
		)
		(pad "CM67" smd circle
			(at 17.89176 6.398514 270)
			(size 0.4318 0.4318)
			(layers "F.Cu" "F.Mask" "F.Paste")
			(net "GND")
		)
		(pad "CM69" smd circle
			(at 19.519392 6.398514 270)
			(size 0.4318 0.4318)
			(layers "F.Cu" "F.Mask" "F.Paste")
			(net "NC_CPU0_PE3_APROBE<1>")
		)
		(pad "CM71" smd circle
			(at 21.147278 6.398514 270)
			(size 0.4318 0.4318)
			(layers "F.Cu" "F.Mask" "F.Paste")
			(net "SMB_S3M_CPU0_PIROM_3V3AUX_SDA_1")
		)
		(pad "CM73" smd circle
			(at 22.77491 6.398514 270)
			(size 0.4318 0.4318)
			(layers "F.Cu" "F.Mask" "F.Paste")
			(net "PVCCFA_EHV_FIVRA_CPU0")
		)
		(pad "CM75" smd circle
			(at 24.402796 6.398514 270)
			(size 0.4318 0.4318)
			(layers "F.Cu" "F.Mask" "F.Paste")
			(net "Net_691")
		)
		(pad "CM77" smd circle
			(at 26.030682 6.398514 270)
			(size 0.4318 0.4318)
			(layers "F.Cu" "F.Mask" "F.Paste")
			(net "Net_669")
		)
		(pad "CM79" smd circle
			(at 27.658314 6.398514 270)
			(size 0.4318 0.4318)
			(layers "F.Cu" "F.Mask" "F.Paste")
			(net "GND")
		)
		(pad "CM81" smd circle
			(at 29.2862 6.398514 270)
			(size 0.4318 0.4318)
			(layers "F.Cu" "F.Mask" "F.Paste")
			(net "GND")
		)
		(pad "CM83" smd circle
			(at 30.914086 6.398514 270)
			(size 0.4318 0.4318)
			(layers "F.Cu" "F.Mask" "F.Paste")
			(net "GND")
		)
		(pad "CM85" smd circle
			(at 32.541718 6.398514 270)
			(size 0.4318 0.4318)
			(layers "F.Cu" "F.Mask" "F.Paste")
			(net "GND")
		)
		(pad "CM87" smd circle
			(at 34.169604 6.398514 270)
			(size 0.4318 0.4318)
			(layers "F.Cu" "F.Mask" "F.Paste")
			(net "PVCCIN_CPU0")
		)
		(pad "CM89" smd circle
			(at 35.797236 6.398514 270)
			(size 0.4318 0.4318)
			(layers "F.Cu" "F.Mask" "F.Paste")
			(net "PVCCIN_CPU0")
		)
		(pad "CM91" smd oval
			(at 37.425122 6.398514)
			(size 0.381 0.4826)
			(drill
				(offset 0 -0.0508)
			)
			(layers "F.Cu" "F.Mask" "F.Paste")
			(net "PVCCIN_CPU0")
		)
		(pad "CN1" smd oval
			(at -37.425122 6.758686 180)
			(size 0.381 0.4826)
			(drill
				(offset 0 -0.0508)
			)
			(layers "F.Cu" "F.Mask" "F.Paste")
			(net "UPI_CPU1_CPU0_P0P1_DP<17>")
		)
		(pad "CN3" smd circle
			(at -35.797236 6.758686 270)
			(size 0.4318 0.4318)
			(layers "F.Cu" "F.Mask" "F.Paste")
			(net "PVCCINFAON_CPU0")
		)
		(pad "CN5" smd circle
			(at -34.169604 6.758686 270)
			(size 0.4318 0.4318)
			(layers "F.Cu" "F.Mask" "F.Paste")
			(net "UPI_CPU0_CPU1_P1P0_DP<16>")
		)
		(pad "CN7" smd circle
			(at -32.541718 6.758686 270)
			(size 0.4318 0.4318)
			(layers "F.Cu" "F.Mask" "F.Paste")
			(net "PVCCINFAON_CPU0")
		)
		(pad "CN9" smd circle
			(at -30.914086 6.758686 270)
			(size 0.4318 0.4318)
			(layers "F.Cu" "F.Mask" "F.Paste")
			(net "P5E_CPU0_PE1_RX_DP<0>")
		)
		(pad "CN11" smd circle
			(at -29.2862 6.758686 270)
			(size 0.4318 0.4318)
			(layers "F.Cu" "F.Mask" "F.Paste")
			(net "PVCCINFAON_CPU0")
		)
		(pad "CN13" smd circle
			(at -27.658314 6.758686 270)
			(size 0.4318 0.4318)
			(layers "F.Cu" "F.Mask" "F.Paste")
			(net "P5E_CPU0_PE1_TX_DN<1>")
		)
		(pad "CN15" smd circle
			(at -26.030682 6.758686 270)
			(size 0.4318 0.4318)
			(layers "F.Cu" "F.Mask" "F.Paste")
			(net "PVCCINFAON_CPU0")
		)
		(pad "CN17" smd circle
			(at -24.402796 6.758686 270)
			(size 0.4318 0.4318)
			(layers "F.Cu" "F.Mask" "F.Paste")
			(net "DMI_CPU0_PCH_TX_DP<7>")
		)
		(pad "CN19" smd circle
			(at -22.77491 6.758686 270)
			(size 0.4318 0.4318)
			(layers "F.Cu" "F.Mask" "F.Paste")
			(net "PVCCINFAON_CPU0")
		)
		(pad "CN21" smd circle
			(at -21.147278 6.758686 270)
			(size 0.4318 0.4318)
			(layers "F.Cu" "F.Mask" "F.Paste")
			(net "TP_IBL_SLPS4_CPU0_R_N")
		)
		(pad "CN23" smd circle
			(at -19.519392 6.758686 270)
			(size 0.4318 0.4318)
			(layers "F.Cu" "F.Mask" "F.Paste")
			(net "TP_FM_IBL_ADR_ACK_CPU0")
		)
		(pad "CN25" smd circle
			(at -17.89176 6.758686 270)
			(size 0.4318 0.4318)
			(layers "F.Cu" "F.Mask" "F.Paste")
			(net "H_CPU0_PMSYNC_CPU1_R")
		)
		(pad "CN60" smd circle
			(at 12.19454 6.868668 270)
			(size 0.4318 0.4318)
			(layers "F.Cu" "F.Mask" "F.Paste")
			(net "NC_CPU0_LGSSPARE1")
		)
		(pad "CN62" smd circle
			(at 13.822426 6.868668 270)
			(size 0.4318 0.4318)
			(layers "F.Cu" "F.Mask" "F.Paste")
			(net "NC_CPU0_VIEWPIN_DIE11<1>")
		)
		(pad "CN64" smd circle
			(at 15.450058 6.868668 270)
			(size 0.4318 0.4318)
			(layers "F.Cu" "F.Mask" "F.Paste")
			(net "PVCCINFAON_CPU0")
		)
		(pad "CN66" smd circle
			(at 17.07769 6.868668 270)
			(size 0.4318 0.4318)
			(layers "F.Cu" "F.Mask" "F.Paste")
			(net "PVCCINFAON_CPU0")
		)
		(pad "CN68" smd circle
			(at 18.705576 6.868668 270)
			(size 0.4318 0.4318)
			(layers "F.Cu" "F.Mask" "F.Paste")
			(net "GND")
		)
		(pad "CN70" smd circle
			(at 20.333462 6.868668 270)
			(size 0.4318 0.4318)
			(layers "F.Cu" "F.Mask" "F.Paste")
			(net "GND")
		)
		(pad "CN72" smd circle
			(at 21.961094 6.868668 270)
			(size 0.4318 0.4318)
			(layers "F.Cu" "F.Mask" "F.Paste")
			(net "GND")
		)
		(pad "CN74" smd circle
			(at 23.58898 6.868668 270)
			(size 0.4318 0.4318)
			(layers "F.Cu" "F.Mask" "F.Paste")
			(net "GND")
		)
		(pad "CN76" smd circle
			(at 25.216612 6.868668 270)
			(size 0.4318 0.4318)
			(layers "F.Cu" "F.Mask" "F.Paste")
			(net "GND")
		)
		(pad "CN78" smd circle
			(at 26.844498 6.868668 270)
			(size 0.4318 0.4318)
			(layers "F.Cu" "F.Mask" "F.Paste")
			(net "PVCCFA_EHV_FIVRA_CPU0")
		)
		(pad "CN80" smd circle
			(at 28.472384 6.868668 270)
			(size 0.4318 0.4318)
			(layers "F.Cu" "F.Mask" "F.Paste")
			(net "GND")
		)
		(pad "CN82" smd circle
			(at 30.100016 6.868668 270)
			(size 0.4318 0.4318)
			(layers "F.Cu" "F.Mask" "F.Paste")
			(net "GND")
		)
		(pad "CN84" smd circle
			(at 31.727902 6.868668 270)
			(size 0.4318 0.4318)
			(layers "F.Cu" "F.Mask" "F.Paste")
			(net "GND")
		)
		(pad "CN86" smd circle
			(at 33.355534 6.868668 270)
			(size 0.4318 0.4318)
			(layers "F.Cu" "F.Mask" "F.Paste")
			(net "GND")
		)
		(pad "CN88" smd circle
			(at 34.98342 6.868668 270)
			(size 0.4318 0.4318)
			(layers "F.Cu" "F.Mask" "F.Paste")
			(net "PVCCIN_CPU0")
		)
		(pad "CN90" smd circle
			(at 36.611306 6.868668 270)
			(size 0.4318 0.4318)
			(layers "F.Cu" "F.Mask" "F.Paste")
			(net "PVCCIN_CPU0")
		)
		(pad "CP2" smd circle
			(at -36.611306 7.228332 270)
			(size 0.4318 0.4318)
			(layers "F.Cu" "F.Mask" "F.Paste")
			(net "UPI_CPU1_CPU0_P0P1_DN<17>")
		)
		(pad "CP4" smd circle
			(at -34.98342 7.228332 270)
			(size 0.4318 0.4318)
			(layers "F.Cu" "F.Mask" "F.Paste")
			(net "GND")
		)
		(pad "CP6" smd circle
			(at -33.355534 7.228332 270)
			(size 0.4318 0.4318)
			(layers "F.Cu" "F.Mask" "F.Paste")
			(net "UPI_CPU0_CPU1_P1P0_DN<16>")
		)
		(pad "CP8" smd circle
			(at -31.727902 7.228332 270)
			(size 0.4318 0.4318)
			(layers "F.Cu" "F.Mask" "F.Paste")
			(net "GND")
		)
		(pad "CP10" smd circle
			(at -30.100016 7.228332 270)
			(size 0.4318 0.4318)
			(layers "F.Cu" "F.Mask" "F.Paste")
			(net "P5E_CPU0_PE1_RX_DN<0>")
		)
		(pad "CP12" smd circle
			(at -28.472384 7.228332 270)
			(size 0.4318 0.4318)
			(layers "F.Cu" "F.Mask" "F.Paste")
			(net "GND")
		)
		(pad "CP14" smd circle
			(at -26.844498 7.228332 270)
			(size 0.4318 0.4318)
			(layers "F.Cu" "F.Mask" "F.Paste")
			(net "P5E_CPU0_PE1_TX_DN<0>")
		)
		(pad "CP16" smd circle
			(at -25.216612 7.228332 270)
			(size 0.4318 0.4318)
			(layers "F.Cu" "F.Mask" "F.Paste")
			(net "GND")
		)
		(pad "CP18" smd circle
			(at -23.58898 7.228332 270)
			(size 0.4318 0.4318)
			(layers "F.Cu" "F.Mask" "F.Paste")
			(net "GND")
		)
		(pad "CP20" smd circle
			(at -21.961094 7.228332 270)
			(size 0.4318 0.4318)
			(layers "F.Cu" "F.Mask" "F.Paste")
			(net "H_CPU0_PM_FAST_WAKE_N")
		)
		(pad "CP22" smd circle
			(at -20.333462 7.228332 270)
			(size 0.4318 0.4318)
			(layers "F.Cu" "F.Mask" "F.Paste")
			(net "TP_JTAG_CPU0_PLD_TDO")
		)
		(pad "CP24" smd circle
			(at -18.705576 7.228332 270)
			(size 0.4318 0.4318)
			(layers "F.Cu" "F.Mask" "F.Paste")
			(net "TP_FM_IBL_ADR_COMPLETE_CPU0_R")
		)
		(pad "CP26" smd circle
			(at -17.07769 7.228332 270)
			(size 0.4318 0.4318)
			(layers "F.Cu" "F.Mask" "F.Paste")
			(net "TP_H_SBLINK2_CPU0_PMDOWN")
		)
		(pad "CP61" smd circle
			(at 13.008356 7.338314 270)
			(size 0.4318 0.4318)
			(layers "F.Cu" "F.Mask" "F.Paste")
			(net "NC_CPU0_LGSSPARE5")
		)
		(pad "CP63" smd circle
			(at 14.635988 7.338314 270)
			(size 0.4318 0.4318)
			(layers "F.Cu" "F.Mask" "F.Paste")
			(net "PVCCINFAON_CPU0")
		)
		(pad "CP65" smd circle
			(at 16.263874 7.338314 270)
			(size 0.4318 0.4318)
			(layers "F.Cu" "F.Mask" "F.Paste")
			(net "PVCCINFAON_CPU0")
		)
		(pad "CP67" smd circle
			(at 17.89176 7.338314 270)
			(size 0.4318 0.4318)
			(layers "F.Cu" "F.Mask" "F.Paste")
			(net "PVCCINFAON_CPU0")
		)
		(pad "CP69" smd circle
			(at 19.519392 7.338314 270)
			(size 0.4318 0.4318)
			(layers "F.Cu" "F.Mask" "F.Paste")
			(net "NC_CPU0_UPI3_APROBE<0>")
		)
		(pad "CP71" smd circle
			(at 21.147278 7.338314 270)
			(size 0.4318 0.4318)
			(layers "F.Cu" "F.Mask" "F.Paste")
			(net "PD_PIROM_CPU0_ADDR2")
		)
		(pad "CP73" smd circle
			(at 22.77491 7.338314 270)
			(size 0.4318 0.4318)
			(layers "F.Cu" "F.Mask" "F.Paste")
			(net "PVCCFA_EHV_FIVRA_CPU0")
		)
		(pad "CP75" smd circle
			(at 24.402796 7.338314 270)
			(size 0.4318 0.4318)
			(layers "F.Cu" "F.Mask" "F.Paste")
			(net "GND")
		)
		(pad "CP77" smd circle
			(at 26.030682 7.338314 270)
			(size 0.4318 0.4318)
			(layers "F.Cu" "F.Mask" "F.Paste")
			(net "GND")
		)
		(pad "CP79" smd circle
			(at 27.658314 7.338314 270)
			(size 0.4318 0.4318)
			(layers "F.Cu" "F.Mask" "F.Paste")
			(net "GND")
		)
		(pad "CP81" smd circle
			(at 29.2862 7.338314 270)
			(size 0.4318 0.4318)
			(layers "F.Cu" "F.Mask" "F.Paste")
			(net "GND")
		)
		(pad "CP83" smd circle
			(at 30.914086 7.338314 270)
			(size 0.4318 0.4318)
			(layers "F.Cu" "F.Mask" "F.Paste")
			(net "GND")
		)
		(pad "CP85" smd circle
			(at 32.541718 7.338314 270)
			(size 0.4318 0.4318)
			(layers "F.Cu" "F.Mask" "F.Paste")
			(net "P5E_CPU0_PE3_TX_DN<15>")
		)
		(pad "CP87" smd circle
			(at 34.169604 7.338314 270)
			(size 0.4318 0.4318)
			(layers "F.Cu" "F.Mask" "F.Paste")
			(net "GND")
		)
		(pad "CP89" smd circle
			(at 35.797236 7.338314 270)
			(size 0.4318 0.4318)
			(layers "F.Cu" "F.Mask" "F.Paste")
			(net "PVCCIN_CPU0")
		)
		(pad "CP91" smd oval
			(at 37.425122 7.338314)
			(size 0.381 0.4826)
			(drill
				(offset 0 -0.0508)
			)
			(layers "F.Cu" "F.Mask" "F.Paste")
			(net "GND")
		)
		(pad "CR1" smd oval
			(at -37.425122 7.698486 180)
			(size 0.381 0.4826)
			(drill
				(offset 0 -0.0508)
			)
			(layers "F.Cu" "F.Mask" "F.Paste")
			(net "GND")
		)
		(pad "CR3" smd circle
			(at -35.797236 7.698486 270)
			(size 0.4318 0.4318)
			(layers "F.Cu" "F.Mask" "F.Paste")
			(net "UPI_CPU1_CPU0_P0P1_DN<16>")
		)
	)
)
